# S9S_MB_2U (Grand Teton) — schematic netlist excerpt (pin names and nets, part order shuffled) for the footprints in the layout excerpt that follows; sources: Cadence DE-HDL packaged netlist, KiCad conversion of 03242023_DA0F0TMBIJ0_F0T_Motherboard_J_brd_V01_OCP.brd

C522  Q_CAP  47UF 4V 20% X6S  pkg C0805  page 75 : A = PVCCINFAON_CPU0 ; B = GND
C2340  Q_CAP  1000PF 50V 5% EMPTY  pkg 0402  page 145 : A = HGX_DETECT_N_ISO ; B = GND
PR329  Q_RES  0 5% CHIP  pkg 0402LF  page 285 : A = PVCCIN_CPU1_VOS2 ; B = PVCCIN_CPU1

(kicad_pcb
	(version 20260206)
	(generator "pcbnew")
	(generator_version "10.0")
	(general
		(thickness 1.6)
		(legacy_teardrops no)
	)
	(paper "A4")
	(title_block
		(title "03242023_DA0F0TMBIJ0_F0T_Motherboard_J_brd_V01_OCP.brd")
		(comment 1 "Grand Teton / footprints 5645-5647 of 6105")
	)
	(layers
		(0 "F.Cu" signal "TOP")
		(4 "In1.Cu" signal "GND")
		(6 "In2.Cu" signal "IN1")
		(8 "In3.Cu" signal "GND1")
		(10 "In4.Cu" signal "IN2")
		(12 "In5.Cu" signal "GND2")
		(14 "In6.Cu" signal "IN3")
		(16 "In7.Cu" signal "GND3")
		(18 "In8.Cu" signal "VCC")
		(20 "In9.Cu" signal "VCC1")
		(22 "In10.Cu" signal "GND4")
		(24 "In11.Cu" signal "IN4")
		(26 "In12.Cu" signal "GND5")
		(28 "In13.Cu" signal "IN5")
		(30 "In14.Cu" signal "GND6")
		(32 "In15.Cu" signal "IN6")
		(34 "In16.Cu" signal "GND7")
		(2 "B.Cu" signal "BOTTOM")
		(9 "F.Adhes" user "F.Adhesive")
		(11 "B.Adhes" user "B.Adhesive")
		(13 "F.Paste" user "Package Geometry/Pastemask Top")
		(15 "B.Paste" user "Package Geometry/Pastemask Bottom")
		(5 "F.SilkS" user "Ref Des/Silkscreen Top")
		(7 "B.SilkS" user "Ref Des/Silkscreen Bottom")
		(1 "F.Mask" user "Board Geometry/Soldermask Top")
		(3 "B.Mask" user "Board Geometry/Soldermask Bottom")
		(17 "Dwgs.User" user "User.Drawings")
		(19 "Cmts.User" user "User.Comments")
		(21 "Eco1.User" user "User.Eco1")
		(23 "Eco2.User" user "User.Eco2")
		(25 "Edge.Cuts" user "Board Geometry/Outline")
		(27 "Margin" user)
		(31 "F.CrtYd" user "Package Geometry/Place Bound Top")
		(29 "B.CrtYd" user "Package Geometry/Place Bound Bottom")
		(35 "F.Fab" user "Ref Des/Assembly Top")
		(33 "B.Fab" user "Ref Des/Assembly Bottom")
	)
	(footprint ""
		(layer "B.Cu")
		(at 97.46996 -422.143428 -90)
		(property "Reference" "C2340"
			(at 0 0 90)
			(layer "B.SilkS")
			(hide yes)
			(effects
				(font
					(size 1.27 1.27)
				)
				(justify mirror)
			)
		)
		(property "Value" ""
			(at 0 0 90)
			(layer "B.Fab")
			(effects
				(font
					(size 1.27 1.27)
				)
				(justify mirror)
			)
		)
		(duplicate_pad_numbers_are_jumpers no)
		(fp_line
			(start -0.7874 0.4064)
			(end 0.7874 0.4064)
			(stroke
				(width 0.1524)
				(type default)
			)
			(layer "B.SilkS")
		)
		(fp_line
			(start 0.7874 0.4064)
			(end 0.7874 -0.4064)
			(stroke
				(width 0.1524)
				(type default)
			)
			(layer "B.SilkS")
		)
		(fp_line
			(start -0.7874 -0.4064)
			(end -0.7874 0.4064)
			(stroke
				(width 0.1524)
				(type default)
			)
			(layer "B.SilkS")
		)
		(fp_line
			(start 0.7874 -0.4064)
			(end -0.7874 -0.4064)
			(stroke
				(width 0.1524)
				(type default)
			)
			(layer "B.SilkS")
		)
		(fp_line
			(start -0.67945 0.3048)
			(end -0.120396 0.3048)
			(stroke
				(width 0.1)
				(type default)
			)
			(layer "B.Fab")
		)
		(fp_line
			(start -0.120396 0.3048)
			(end -0.120396 0.2794)
			(stroke
				(width 0.1)
				(type default)
			)
			(layer "B.Fab")
		)
		(fp_line
			(start 0.12065 0.3048)
			(end 0.67945 0.3048)
			(stroke
				(width 0.1)
				(type default)
			)
			(layer "B.Fab")
		)
		(fp_line
			(start 0.67945 0.3048)
			(end 0.67945 -0.305054)
			(stroke
				(width 0.1)
				(type default)
			)
			(layer "B.Fab")
		)
		(fp_line
			(start -0.120396 0.2794)
			(end 0.12065 0.2794)
			(stroke
				(width 0.1)
				(type default)
			)
			(layer "B.Fab")
		)
		(fp_line
			(start 0.12065 0.2794)
			(end 0.12065 0.3048)
			(stroke
				(width 0.1)
				(type default)
			)
			(layer "B.Fab")
		)
		(fp_line
			(start -0.12065 -0.2794)
			(end -0.12065 -0.3048)
			(stroke
				(width 0.1)
				(type default)
			)
			(layer "B.Fab")
		)
		(fp_line
			(start 0.12065 -0.2794)
			(end -0.12065 -0.2794)
			(stroke
				(width 0.1)
				(type default)
			)
			(layer "B.Fab")
		)
		(fp_line
			(start -0.67945 -0.3048)
			(end -0.67945 0.3048)
			(stroke
				(width 0.1)
				(type default)
			)
			(layer "B.Fab")
		)
		(fp_line
			(start -0.12065 -0.3048)
			(end -0.67945 -0.3048)
			(stroke
				(width 0.1)
				(type default)
			)
			(layer "B.Fab")
		)
		(fp_line
			(start 0.12065 -0.305054)
			(end 0.12065 -0.2794)
			(stroke
				(width 0.1)
				(type default)
			)
			(layer "B.Fab")
		)
		(fp_line
			(start 0.67945 -0.305054)
			(end 0.12065 -0.305054)
			(stroke
				(width 0.1)
				(type default)
			)
			(layer "B.Fab")
		)
		(pad "1" smd circle
			(at 0.40005 0 90)
			(size 0 0)
			(layers "B.Cu" "B.Mask" "B.Paste")
			(net "HGX_DETECT_N_ISO")
		)
		(pad "2" smd circle
			(at -0.40005 0 90)
			(size 0 0)
			(layers "B.Cu" "B.Mask" "B.Paste")
			(net "GND")
		)
	)
	(footprint ""
		(layer "B.Cu")
		(at 101.717348 -336.192368 -90)
		(property "Reference" "PR329"
			(at 0 0 90)
			(layer "B.SilkS")
			(hide yes)
			(effects
				(font
					(size 1.27 1.27)
				)
				(justify mirror)
			)
		)
		(property "Value" ""
			(at 0 0 90)
			(layer "B.Fab")
			(effects
				(font
					(size 1.27 1.27)
				)
				(justify mirror)
			)
		)
		(duplicate_pad_numbers_are_jumpers no)
		(fp_line
			(start -0.7874 0.4064)
			(end 0.7874 0.4064)
			(stroke
				(width 0.1524)
				(type default)
			)
			(layer "B.SilkS")
		)
		(fp_line
			(start 0.7874 0.4064)
			(end 0.7874 -0.4064)
			(stroke
				(width 0.1524)
				(type default)
			)
			(layer "B.SilkS")
		)
		(fp_line
			(start -0.7874 -0.4064)
			(end -0.7874 0.4064)
			(stroke
				(width 0.1524)
				(type default)
			)
			(layer "B.SilkS")
		)
		(fp_line
			(start 0.7874 -0.4064)
			(end -0.7874 -0.4064)
			(stroke
				(width 0.1524)
				(type default)
			)
			(layer "B.SilkS")
		)
		(fp_line
			(start -0.67945 0.3048)
			(end -0.120396 0.3048)
			(stroke
				(width 0.1)
				(type default)
			)
			(layer "B.Fab")
		)
		(fp_line
			(start -0.120396 0.3048)
			(end -0.120396 0.2794)
			(stroke
				(width 0.1)
				(type default)
			)
			(layer "B.Fab")
		)
		(fp_line
			(start 0.12065 0.3048)
			(end 0.67945 0.3048)
			(stroke
				(width 0.1)
				(type default)
			)
			(layer "B.Fab")
		)
		(fp_line
			(start 0.67945 0.3048)
			(end 0.67945 -0.305054)
			(stroke
				(width 0.1)
				(type default)
			)
			(layer "B.Fab")
		)
		(fp_line
			(start -0.120396 0.2794)
			(end 0.12065 0.2794)
			(stroke
				(width 0.1)
				(type default)
			)
			(layer "B.Fab")
		)
		(fp_line
			(start 0.12065 0.2794)
			(end 0.12065 0.3048)
			(stroke
				(width 0.1)
				(type default)
			)
			(layer "B.Fab")
		)
		(fp_line
			(start -0.12065 -0.2794)
			(end -0.12065 -0.3048)
			(stroke
				(width 0.1)
				(type default)
			)
			(layer "B.Fab")
		)
		(fp_line
			(start 0.12065 -0.2794)
			(end -0.12065 -0.2794)
			(stroke
				(width 0.1)
				(type default)
			)
			(layer "B.Fab")
		)
		(fp_line
			(start -0.67945 -0.3048)
			(end -0.67945 0.3048)
			(stroke
				(width 0.1)
				(type default)
			)
			(layer "B.Fab")
		)
		(fp_line
			(start -0.12065 -0.3048)
			(end -0.67945 -0.3048)
			(stroke
				(width 0.1)
				(type default)
			)
			(layer "B.Fab")
		)
		(fp_line
			(start 0.12065 -0.305054)
			(end 0.12065 -0.2794)
			(stroke
				(width 0.1)
				(type default)
			)
			(layer "B.Fab")
		)
		(fp_line
			(start 0.67945 -0.305054)
			(end 0.12065 -0.305054)
			(stroke
				(width 0.1)
				(type default)
			)
			(layer "B.Fab")
		)
		(pad "1" smd circle
			(at 0.40005 0 90)
			(size 0 0)
			(layers "B.Cu" "B.Mask" "B.Paste")
			(net "PVCCIN_CPU1_VOS2")
		)
		(pad "2" smd circle
			(at -0.40005 0 90)
			(size 0 0)
			(layers "B.Cu" "B.Mask" "B.Paste")
			(net "PVCCIN_CPU1")
		)
	)
	(footprint ""
		(layer "B.Cu")
		(at 367.898934 -259.531866 90)
		(property "Reference" "C522"
			(at 0 0 90)
			(layer "B.SilkS")
			(hide yes)
			(effects
				(font
					(size 1.27 1.27)
				)
				(justify mirror)
			)
		)
		(property "Value" ""
			(at 0 0 90)
			(layer "B.Fab")
			(effects
				(font
					(size 1.27 1.27)
				)
				(justify mirror)
			)
		)
		(duplicate_pad_numbers_are_jumpers no)
		(fp_line
			(start 1.524 -0.762)
			(end -1.524 -0.762)
			(stroke
				(width 0.1524)
				(type default)
			)
			(layer "B.SilkS")
		)
		(fp_line
			(start -1.524 -0.762)
			(end -1.524 0.762)
			(stroke
				(width 0.1524)
				(type default)
			)
			(layer "B.SilkS")
		)
		(fp_line
			(start 1.524 0.762)
			(end 1.524 -0.762)
			(stroke
				(width 0.1524)
				(type default)
			)
			(layer "B.SilkS")
		)
		(fp_line
			(start -1.524 0.762)
			(end 1.524 0.762)
			(stroke
				(width 0.1524)
				(type default)
			)
			(layer "B.SilkS")
		)
		(fp_line
			(start 1.1049 -0.724916)
			(end 1.1049 0.724916)
			(stroke
				(width 0.1)
				(type default)
			)
			(layer "B.Fab")
		)
		(fp_line
			(start -1.1049 -0.724916)
			(end 1.1049 -0.724916)
			(stroke
				(width 0.1)
				(type default)
			)
			(layer "B.Fab")
		)
		(fp_line
			(start 1.1049 0.724916)
			(end -1.1049 0.724916)
			(stroke
				(width 0.1)
				(type default)
			)
			(layer "B.Fab")
		)
		(fp_line
			(start -1.1049 0.724916)
			(end -1.1049 -0.724916)
			(stroke
				(width 0.1)
				(type default)
			)
			(layer "B.Fab")
		)
		(pad "1" smd rect
			(at 0.889 0 90)
			(size 1.016 1.27)
			(layers "B.Cu" "B.Mask" "B.Paste")
			(net "PVCCINFAON_CPU0")
		)
		(pad "2" smd rect
			(at -0.889 0 90)
			(size 1.016 1.27)
			(layers "B.Cu" "B.Mask" "B.Paste")
			(net "GND")
		)
	)
)
